# T6G (Grand Teton) — schematic netlist excerpt (pin names and nets, part order shuffled) for the footprints in the layout excerpt that follows; sources: Cadence DE-HDL packaged netlist, KiCad conversion of 04192023_DAF0TMB3IC0_F0TG_MB_C_brd_V02_OCP.brd

J18  SCONN288_DDR506112002KQ  IO  pkg DDR288S_1-1VXC  page 94
  VIN_BULK0  = P12V_MEM_CPU0
  RFU0  = NC
  VIN_MGMT  = P3V3_AUX
  HSCL  = I3C_SPD_DDRI_CPU0_SCL
  HSDA  = I3C_SPD_DDRI_CPU0_SDA
  VSS0  = GND
  DQ0_A  = M_I_CPU0_SA_DQ<0>
  VSS1  = GND
  DQ1_A  = M_I_CPU0_SA_DQ<1>
  VSS2  = GND
  DQS0_A_T  = M_I_CPU0_SA_DQS_DP<0>
  DQS0_A_C  = M_I_CPU0_SA_DQS_DN<0>
  VSS3  = GND
  DQ4_A  = M_I_CPU0_SA_DQ<4>
  VSS4  = GND
  DQ5_A  = M_I_CPU0_SA_DQ<5>
  VSS5  = GND
  DQ8_A  = M_I_CPU0_SA_DQ<8>
  VSS6  = GND
  DQ9_A  = M_I_CPU0_SA_DQ<9>
  VSS7  = GND
  DQS1_A_T  = M_I_CPU0_SA_DQS_DP<1>
  DQS1_A_C  = M_I_CPU0_SA_DQS_DN<1>
  VSS8  = GND
  DQ12_A  = M_I_CPU0_SA_DQ<12>
  VSS9  = GND
  DQ13_A  = M_I_CPU0_SA_DQ<13>
  VSS10  = GND
  DQ16_A  = M_I_CPU0_SA_DQ<16>
  VSS11  = GND
  DQ17_A  = M_I_CPU0_SA_DQ<17>
  VSS12  = GND
  DQS2_A_T  = M_I_CPU0_SA_DQS_DP<2>
  DQS2_A_C  = M_I_CPU0_SA_DQS_DN<2>
  VSS13  = GND
  DQ20_A  = M_I_CPU0_SA_DQ<20>
  VSS14  = GND
  DQ21_A  = M_I_CPU0_SA_DQ<21>
  VSS15  = GND
  DQ24_A  = M_I_CPU0_SA_DQ<24>
  VSS16  = GND
  DQ25_A  = M_I_CPU0_SA_DQ<25>
  VSS17  = GND
  DQS3_A_T  = M_I_CPU0_SA_DQS_DP<3>
  DQS3_A_C  = M_I_CPU0_SA_DQS_DN<3>
  VSS18  = GND
  DQ28_A  = M_I_CPU0_SA_DQ<28>
  VSS19  = GND
  DQ29_A  = M_I_CPU0_SA_DQ<29>
  VSS20  = GND
  CB0_A  = M_I_CPU0_SA_CB<0>
  VSS21  = GND
  CB1_A  = M_I_CPU0_SA_CB<1>
  VSS22  = GND
  DQS4_A_T  = M_I_CPU0_SA_DQS_DP<4>
  DQS4_A_C  = M_I_CPU0_SA_DQS_DN<4>
  VSS23  = GND
  CB4_A  = M_I_CPU0_SA_CB<4>
  VSS24  = GND
  CB5_A  = M_I_CPU0_SA_CB<5>
  VSS25  = GND
  ALERT_N  = M_I_CPU0_ALERT_N
  VSS26  = GND
  CS0_A_N  = M_I_CPU0_SA_CS_N<0>
  VSS27  = GND
  CA0_A  = M_I_CPU0_SA_CA<0>
  VSS28  = GND
  CA2_A  = M_I_CPU0_SA_CA<2>
  VSS29  = GND
  CA4_A  = M_I_CPU0_SA_CA<4>
  VSS30  = GND
  CA6_A  = M_I_CPU0_SA_CA<6>
  VSS31  = GND
  PAR_A  = M_I_CPU0_SA_PAR
  VSS32  = GND
  CA0_B  = M_I_CPU0_SB_CA<0>
  VSS33  = GND
  CA2_B  = M_I_CPU0_SB_CA<2>
  VSS34  = GND
  CA4_B  = M_I_CPU0_SB_CA<4>
  VSS35  = GND
  CA6_B  = M_I_CPU0_SB_CA<6>
  VSS36  = GND
  CS0_B_N  = M_I_CPU0_SB_CS_N<0>
  VSS37  = GND
  \lbd||rsp_a_n\  = M_I_CPU0_SA_RSP<0>
  \lbs||rsp_b_n\  = M_I_CPU0_SB_RSP<0>
  VSS38  = GND
  CB4_B  = M_I_CPU0_SB_CB<4>
  VSS39  = GND
  CB5_B  = M_I_CPU0_SB_CB<5>
  VSS40  = GND
  \dqs9_b_t||tdqs9_b_t||dbi4_b_n\  = M_I_CPU0_SB_DQS_DP<9>
  \dqs9_b_c||tdqs9_b_c\  = M_I_CPU0_SB_DQS_DN<9>
  VSS41  = GND
  CB0_B  = M_I_CPU0_SB_CB<0>
  VSS42  = GND
  CB1_B  = M_I_CPU0_SB_CB<1>
  VSS43  = GND
  DQ0_B  = M_I_CPU0_SB_DQ<0>
  VSS44  = GND
  DQ1_B  = M_I_CPU0_SB_DQ<1>
  VSS45  = GND
  DQS0_B_T  = M_I_CPU0_SB_DQS_DP<0>
  DQS0_B_C  = M_I_CPU0_SB_DQS_DN<0>
  VSS46  = GND
  DQ4_B  = M_I_CPU0_SB_DQ<4>
  VSS47  = GND
  DQ5_B  = M_I_CPU0_SB_DQ<5>
  VSS48  = GND
  DQ8_B  = M_I_CPU0_SB_DQ<8>
  VSS49  = GND
  DQ9_B  = M_I_CPU0_SB_DQ<9>
  VSS50  = GND
  DQS1_B_T  = M_I_CPU0_SB_DQS_DP<1>
  DQS1_B_C  = M_I_CPU0_SB_DQS_DN<1>
  VSS51  = GND
  DQ12_B  = M_I_CPU0_SB_DQ<12>
  VSS52  = GND
  DQ13_B  = M_I_CPU0_SB_DQ<13>
  VSS53  = GND
  DQ16_B  = M_I_CPU0_SB_DQ<16>
  VSS54  = GND
  DQ17_B  = M_I_CPU0_SB_DQ<17>
  VSS55  = GND
  DQS2_B_T  = M_I_CPU0_SB_DQS_DP<2>
  DQS2_B_C  = M_I_CPU0_SB_DQS_DN<2>
  VSS56  = GND
  DQ20_B  = M_I_CPU0_SB_DQ<20>
  VSS57  = GND
  DQ21_B  = M_I_CPU0_SB_DQ<21>
  VSS58  = GND
  DQ24_B  = M_I_CPU0_SB_DQ<24>
  VSS59  = GND
  DQ25_B  = M_I_CPU0_SB_DQ<25>
  VSS60  = GND
  DQS3_B_T  = M_I_CPU0_SB_DQS_DP<3>
  DQS3_B_C  = M_I_CPU0_SB_DQS_DN<3>
  VSS61  = GND
  DQ28_B  = M_I_CPU0_SB_DQ<28>
  VSS62  = GND
  DQ29_B  = M_I_CPU0_SB_DQ<29>
  VSS63  = GND
  RFU1  = NC
  VIN_BULK1  = P12V_MEM_CPU0
  VIN_BULK2  = P12V_MEM_CPU0
  \pwr_good||fail_n\  = PWRGD_CHI_CPU0_DIMM
  HAS  = PD_CHI_CPU0_DIMM_SAA
  RFU2  = NC
  RFU3  = NC
  VSS64  = GND
  DQ2_A  = M_I_CPU0_SA_DQ<2>
  VSS65  = GND
  DQ3_A  = M_I_CPU0_SA_DQ<3>
  VSS66  = GND
  \dqs5_a_c||tdqs5_a_c||dqs5_a_t||tdqs5_a_t\  = M_I_CPU0_SA_DQS_DN<5>
  \dqs5_a_t||tdqs5_a_t\  = M_I_CPU0_SA_DQS_DP<5>
  VSS67  = GND
  DQ6_A  = M_I_CPU0_SA_DQ<6>
  VSS68  = GND
  DQ7_A  = M_I_CPU0_SA_DQ<7>
  VSS69  = GND
  DQ10_A  = M_I_CPU0_SA_DQ<10>
  VSS70  = GND
  DQ11_A  = M_I_CPU0_SA_DQ<11>
  VSS71  = GND
  \dqs6_a_c||tdqs6_a_c||dqs6_a_t||tdqs6_a_t\  = M_I_CPU0_SA_DQS_DN<6>
  \dqs6_a_t||tdqs6_a_t\  = M_I_CPU0_SA_DQS_DP<6>
  VSS72  = GND
  DQ14_A  = M_I_CPU0_SA_DQ<14>
  VSS73  = GND
  DQ15_A  = M_I_CPU0_SA_DQ<15>
  VSS74  = GND
  DQ18_A  = M_I_CPU0_SA_DQ<18>
  VSS75  = GND
  DQ19_A  = M_I_CPU0_SA_DQ<19>
  VSS76  = GND
  \dqs7_a_c||tdqs7_a_c\  = M_I_CPU0_SA_DQS_DN<7>
  \dqs7_a_t||tdqs7_a_t\  = M_I_CPU0_SA_DQS_DP<7>
  VSS77  = GND
  DQ22_A  = M_I_CPU0_SA_DQ<22>
  VSS78  = GND
  DQ23_A  = M_I_CPU0_SA_DQ<23>
  VSS79  = GND
  DQ26_A  = M_I_CPU0_SA_DQ<26>
  VSS80  = GND
  DQ27_A  = M_I_CPU0_SA_DQ<27>
  VSS81  = GND
  \dqs8_a_c||tdqs8_a_c\  = M_I_CPU0_SA_DQS_DN<8>
  \dqs8_a_t||tdqs8_a_t\  = M_I_CPU0_SA_DQS_DP<8>
  VSS82  = GND
  DQ30_A  = M_I_CPU0_SA_DQ<30>
  VSS83  = GND
  DQ31_A  = M_I_CPU0_SA_DQ<31>
  VSS84  = GND
  CB2_A  = M_I_CPU0_SA_CB<2>
  VSS85  = GND
  CB3_A  = M_I_CPU0_SA_CB<3>
  VSS86  = GND
  \dqs9_a_c||tdqs9_a_c\  = M_I_CPU0_SA_DQS_DN<9>
  \dqs9_a_t||tdqs9_a_t\  = M_I_CPU0_SA_DQS_DP<9>
  VSS87  = GND
  CB6_A  = M_I_CPU0_SA_CB<6>
  VSS88  = GND
  CB7_A  = M_I_CPU0_SA_CB<7>
  VSS89  = GND
  RESET_N  = M_I_CPU0_RESET_N
  VSS90  = GND
  CS1_A_N  = M_I_CPU0_SA_CS_N<1>
  VSS91  = GND
  CA1_A  = M_I_CPU0_SA_CA<1>
  VSS92  = GND
  CA3_A  = M_I_CPU0_SA_CA<3>
  VSS93  = GND
  CA5_A  = M_I_CPU0_SA_CA<5>
  VSS94  = GND
  CK_T  = M_I_CPU0_CLK_DP<0>
  CK_C  = M_I_CPU0_CLK_DN<0>
  VSS95  = GND
  RFU4  = NC
  CA1_B  = M_I_CPU0_SB_CA<1>
  VSS96  = GND
  CA3_B  = M_I_CPU0_SB_CA<3>
  VSS97  = GND
  CA5_B  = M_I_CPU0_SB_CA<5>
  VSS98  = GND
  PAR_B  = M_I_CPU0_SB_PAR
  VSS99  = GND
  CS1_B_N  = M_I_CPU0_SB_CS_N<1>
  VSS100  = GND
  RFU5  = NC
  RFU6  = NC
  VSS101  = GND
  CB6_B  = M_I_CPU0_SB_CB<6>
  VSS102  = GND
  CB7_B  = M_I_CPU0_SB_CB<7>
  VSS103  = GND
  DQS4_B_C  = M_I_CPU0_SB_DQS_DN<4>
  DQS4_B_T  = M_I_CPU0_SB_DQS_DP<4>
  VSS104  = GND
  CB2_B  = M_I_CPU0_SB_CB<2>
  VSS105  = GND
  CB3_B  = M_I_CPU0_SB_CB<3>
  VSS106  = GND
  DQ2_B  = M_I_CPU0_SB_DQ<2>
  VSS107  = GND
  DQ3_B  = M_I_CPU0_SB_DQ<3>
  VSS108  = GND
  \dqs5_b_c||tdqs5_b_c\  = M_I_CPU0_SB_DQS_DN<5>
  \dqs5_b_t||tdqs5_b_t\  = M_I_CPU0_SB_DQS_DP<5>
  VSS109  = GND
  DQ6_B  = M_I_CPU0_SB_DQ<6>
  VSS110  = GND
  DQ7_B  = M_I_CPU0_SB_DQ<7>
  VSS111  = GND
  DQ10_B  = M_I_CPU0_SB_DQ<10>
  VSS112  = GND
  DQ11_B  = M_I_CPU0_SB_DQ<11>
  VSS113  = GND
  \dqs6_b_c||tdqs6_b_c\  = M_I_CPU0_SB_DQS_DN<6>
  \dqs6_b_t||tdqs6_b_t\  = M_I_CPU0_SB_DQS_DP<6>
  VSS114  = GND
  DQ14_B  = M_I_CPU0_SB_DQ<14>
  VSS115  = GND
  DQ15_B  = M_I_CPU0_SB_DQ<15>
  VSS116  = GND
  DQ18_B  = M_I_CPU0_SB_DQ<18>
  VSS117  = GND
  DQ19_B  = M_I_CPU0_SB_DQ<19>
  VSS118  = GND
  \dqs7_b_c||tdqs7_b_c\  = M_I_CPU0_SB_DQS_DN<7>
  \dqs7_b_t||tdqs7_b_t\  = M_I_CPU0_SB_DQS_DP<7>
  VSS119  = GND
  DQ22_B  = M_I_CPU0_SB_DQ<22>
  VSS120  = GND
  DQ23_B  = M_I_CPU0_SB_DQ<23>
  VSS121  = GND
  DQ26_B  = M_I_CPU0_SB_DQ<26>
  VSS122  = GND
  DQ27_B  = M_I_CPU0_SB_DQ<27>
  VSS123  = GND
  \dqs8_b_c||tdqs8_b_c\  = M_I_CPU0_SB_DQS_DN<8>
  \dqs8_b_t||tdqs8_b_t\  = M_I_CPU0_SB_DQS_DP<8>
  VSS124  = GND
  DQ30_B  = M_I_CPU0_SB_DQ<30>
  VSS125  = GND
  DQ31_B  = M_I_CPU0_SB_DQ<31>
  VSS126  = GND
  G1  = GND
  G2  = GND
  G3  = GND

(kicad_pcb
	(version 20260206)
	(generator "pcbnew")
	(generator_version "10.0")
	(general
		(thickness 1.6)
		(legacy_teardrops no)
	)
	(paper "A4")
	(title_block
		(title "04192023_DAF0TMB3IC0_F0TG_MB_C_brd_V02_OCP.brd")
		(comment 1 "Grand Teton / footprint 4761 of 8354 (J18), pads 231-276 of 291")
	)
	(layers
		(0 "F.Cu" signal "TOP")
		(4 "In1.Cu" signal "GND")
		(6 "In2.Cu" signal "IN1")
		(8 "In3.Cu" signal "GND1")
		(10 "In4.Cu" signal "IN2")
		(12 "In5.Cu" signal "GND2")
		(14 "In6.Cu" signal "IN3")
		(16 "In7.Cu" signal "GND3")
		(18 "In8.Cu" signal "VCC")
		(20 "In9.Cu" signal "VCC1")
		(22 "In10.Cu" signal "GND4")
		(24 "In11.Cu" signal "IN4")
		(26 "In12.Cu" signal "GND5")
		(28 "In13.Cu" signal "IN5")
		(30 "In14.Cu" signal "GND6")
		(32 "In15.Cu" signal "IN6")
		(34 "In16.Cu" signal "GND7")
		(2 "B.Cu" signal "BOTTOM")
		(9 "F.Adhes" user "F.Adhesive")
		(11 "B.Adhes" user "B.Adhesive")
		(13 "F.Paste" user "Package Geometry/Pastemask Top")
		(15 "B.Paste" user "Package Geometry/Pastemask Bottom")
		(5 "F.SilkS" user "Ref Des/Silkscreen Top")
		(7 "B.SilkS" user "Ref Des/Silkscreen Bottom")
		(1 "F.Mask" user "Board Geometry/Soldermask Top")
		(3 "B.Mask" user "Board Geometry/Soldermask Bottom")
		(17 "Dwgs.User" user "User.Drawings")
		(19 "Cmts.User" user "User.Comments")
		(21 "Eco1.User" user "User.Eco1")
		(23 "Eco2.User" user "User.Eco2")
		(25 "Edge.Cuts" user "Board Geometry/Outline")
		(27 "Margin" user)
		(31 "F.CrtYd" user "Package Geometry/Place Bound Top")
		(29 "B.CrtYd" user "Package Geometry/Place Bound Bottom")
		(35 "F.Fab" user "Ref Des/Assembly Top")
		(33 "B.Fab" user "Ref Des/Assembly Bottom")
	)
	(footprint ""
		(layer "F.Cu")
		(at 429.506126 -255.560068 180)
		(property "Reference" "J18"
			(at 0.484632 -81.752948 0)
			(unlocked yes)
			(layer "F.SilkS")
			(effects
				(font
					(size 0.7874 0.5842)
					(thickness 0.1524)
				)
			)
		)
		(property "Value" ""
			(at 0 0 180)
			(layer "F.Fab")
			(effects
				(font
					(size 1.27 1.27)
				)
			)
		)
		(duplicate_pad_numbers_are_jumpers no)
		(pad "231" smd rect
			(at 2.050034 14.875002 90)
			(size 0.519938 1.4986)
			(layers "F.Cu" "F.Mask" "F.Paste")
			(net "Net_2366")
		)
		(pad "232" smd rect
			(at 2.050034 15.724886 90)
			(size 0.519938 1.4986)
			(layers "F.Cu" "F.Mask" "F.Paste")
			(net "Net_2367")
		)
		(pad "233" smd rect
			(at 2.050034 16.575024 90)
			(size 0.519938 1.4986)
			(layers "F.Cu" "F.Mask" "F.Paste")
			(net "GND")
		)
		(pad "234" smd rect
			(at 2.050034 17.424908 90)
			(size 0.519938 1.4986)
			(layers "F.Cu" "F.Mask" "F.Paste")
			(net "M_I_CPU0_SB_CB<6>")
		)
		(pad "235" smd rect
			(at 2.050034 18.275046 90)
			(size 0.519938 1.4986)
			(layers "F.Cu" "F.Mask" "F.Paste")
			(net "GND")
		)
		(pad "236" smd rect
			(at 2.050034 19.12493 90)
			(size 0.519938 1.4986)
			(layers "F.Cu" "F.Mask" "F.Paste")
			(net "M_I_CPU0_SB_CB<7>")
		)
		(pad "237" smd rect
			(at 2.050034 19.975068 90)
			(size 0.519938 1.4986)
			(layers "F.Cu" "F.Mask" "F.Paste")
			(net "GND")
		)
		(pad "238" smd rect
			(at 2.050034 20.824952 90)
			(size 0.519938 1.4986)
			(layers "F.Cu" "F.Mask" "F.Paste")
			(net "M_I_CPU0_SB_DQS_DN<4>")
		)
		(pad "239" smd rect
			(at 2.050034 21.67509 90)
			(size 0.519938 1.4986)
			(layers "F.Cu" "F.Mask" "F.Paste")
			(net "M_I_CPU0_SB_DQS_DP<4>")
		)
		(pad "240" smd rect
			(at 2.050034 22.524974 90)
			(size 0.519938 1.4986)
			(layers "F.Cu" "F.Mask" "F.Paste")
			(net "GND")
		)
		(pad "241" smd rect
			(at 2.050034 23.375112 90)
			(size 0.519938 1.4986)
			(layers "F.Cu" "F.Mask" "F.Paste")
			(net "M_I_CPU0_SB_CB<2>")
		)
		(pad "242" smd rect
			(at 2.050034 24.224996 90)
			(size 0.519938 1.4986)
			(layers "F.Cu" "F.Mask" "F.Paste")
			(net "GND")
		)
		(pad "243" smd rect
			(at 2.050034 25.07488 90)
			(size 0.519938 1.4986)
			(layers "F.Cu" "F.Mask" "F.Paste")
			(net "M_I_CPU0_SB_CB<3>")
		)
		(pad "244" smd rect
			(at 2.050034 25.925018 90)
			(size 0.519938 1.4986)
			(layers "F.Cu" "F.Mask" "F.Paste")
			(net "GND")
		)
		(pad "245" smd rect
			(at 2.050034 26.774902 90)
			(size 0.519938 1.4986)
			(layers "F.Cu" "F.Mask" "F.Paste")
			(net "M_I_CPU0_SB_DQ<2>")
		)
		(pad "246" smd rect
			(at 2.050034 27.62504 90)
			(size 0.519938 1.4986)
			(layers "F.Cu" "F.Mask" "F.Paste")
			(net "GND")
		)
		(pad "247" smd rect
			(at 2.050034 28.474924 90)
			(size 0.519938 1.4986)
			(layers "F.Cu" "F.Mask" "F.Paste")
			(net "M_I_CPU0_SB_DQ<3>")
		)
		(pad "248" smd rect
			(at 2.050034 29.325062 90)
			(size 0.519938 1.4986)
			(layers "F.Cu" "F.Mask" "F.Paste")
			(net "GND")
		)
		(pad "249" smd rect
			(at 2.050034 30.174946 90)
			(size 0.519938 1.4986)
			(layers "F.Cu" "F.Mask" "F.Paste")
			(net "M_I_CPU0_SB_DQS_DN<5>")
		)
		(pad "250" smd rect
			(at 2.050034 31.025084 90)
			(size 0.519938 1.4986)
			(layers "F.Cu" "F.Mask" "F.Paste")
			(net "M_I_CPU0_SB_DQS_DP<5>")
		)
		(pad "251" smd rect
			(at 2.050034 31.874968 90)
			(size 0.519938 1.4986)
			(layers "F.Cu" "F.Mask" "F.Paste")
			(net "GND")
		)
		(pad "252" smd rect
			(at 2.050034 32.725106 90)
			(size 0.519938 1.4986)
			(layers "F.Cu" "F.Mask" "F.Paste")
			(net "M_I_CPU0_SB_DQ<6>")
		)
		(pad "253" smd rect
			(at 2.050034 33.57499 90)
			(size 0.519938 1.4986)
			(layers "F.Cu" "F.Mask" "F.Paste")
			(net "GND")
		)
		(pad "254" smd rect
			(at 2.050034 34.425128 90)
			(size 0.519938 1.4986)
			(layers "F.Cu" "F.Mask" "F.Paste")
			(net "M_I_CPU0_SB_DQ<7>")
		)
		(pad "255" smd rect
			(at 2.050034 35.275012 90)
			(size 0.519938 1.4986)
			(layers "F.Cu" "F.Mask" "F.Paste")
			(net "GND")
		)
		(pad "256" smd rect
			(at 2.050034 36.124896 90)
			(size 0.519938 1.4986)
			(layers "F.Cu" "F.Mask" "F.Paste")
			(net "M_I_CPU0_SB_DQ<10>")
		)
		(pad "257" smd rect
			(at 2.050034 36.975034 90)
			(size 0.519938 1.4986)
			(layers "F.Cu" "F.Mask" "F.Paste")
			(net "GND")
		)
		(pad "258" smd rect
			(at 2.050034 37.824918 90)
			(size 0.519938 1.4986)
			(layers "F.Cu" "F.Mask" "F.Paste")
			(net "M_I_CPU0_SB_DQ<11>")
		)
		(pad "259" smd rect
			(at 2.050034 38.675056 90)
			(size 0.519938 1.4986)
			(layers "F.Cu" "F.Mask" "F.Paste")
			(net "GND")
		)
		(pad "260" smd rect
			(at 2.050034 39.52494 90)
			(size 0.519938 1.4986)
			(layers "F.Cu" "F.Mask" "F.Paste")
			(net "M_I_CPU0_SB_DQS_DN<6>")
		)
		(pad "261" smd rect
			(at 2.050034 40.375078 90)
			(size 0.519938 1.4986)
			(layers "F.Cu" "F.Mask" "F.Paste")
			(net "M_I_CPU0_SB_DQS_DP<6>")
		)
		(pad "262" smd rect
			(at 2.050034 41.224962 90)
			(size 0.519938 1.4986)
			(layers "F.Cu" "F.Mask" "F.Paste")
			(net "GND")
		)
		(pad "263" smd rect
			(at 2.050034 42.0751 90)
			(size 0.519938 1.4986)
			(layers "F.Cu" "F.Mask" "F.Paste")
			(net "M_I_CPU0_SB_DQ<14>")
		)
		(pad "264" smd rect
			(at 2.050034 42.924984 90)
			(size 0.519938 1.4986)
			(layers "F.Cu" "F.Mask" "F.Paste")
			(net "GND")
		)
		(pad "265" smd rect
			(at 2.050034 43.775122 90)
			(size 0.519938 1.4986)
			(layers "F.Cu" "F.Mask" "F.Paste")
			(net "M_I_CPU0_SB_DQ<15>")
		)
		(pad "266" smd rect
			(at 2.050034 44.625006 90)
			(size 0.519938 1.4986)
			(layers "F.Cu" "F.Mask" "F.Paste")
			(net "GND")
		)
		(pad "267" smd rect
			(at 2.050034 45.47489 90)
			(size 0.519938 1.4986)
			(layers "F.Cu" "F.Mask" "F.Paste")
			(net "M_I_CPU0_SB_DQ<18>")
		)
		(pad "268" smd rect
			(at 2.050034 46.325028 90)
			(size 0.519938 1.4986)
			(layers "F.Cu" "F.Mask" "F.Paste")
			(net "GND")
		)
		(pad "269" smd rect
			(at 2.050034 47.174912 90)
			(size 0.519938 1.4986)
			(layers "F.Cu" "F.Mask" "F.Paste")
			(net "M_I_CPU0_SB_DQ<19>")
		)
		(pad "270" smd rect
			(at 2.050034 48.02505 90)
			(size 0.519938 1.4986)
			(layers "F.Cu" "F.Mask" "F.Paste")
			(net "GND")
		)
		(pad "271" smd rect
			(at 2.050034 48.874934 90)
			(size 0.519938 1.4986)
			(layers "F.Cu" "F.Mask" "F.Paste")
			(net "M_I_CPU0_SB_DQS_DN<7>")
		)
		(pad "272" smd rect
			(at 2.050034 49.725072 90)
			(size 0.519938 1.4986)
			(layers "F.Cu" "F.Mask" "F.Paste")
			(net "M_I_CPU0_SB_DQS_DP<7>")
		)
		(pad "273" smd rect
			(at 2.050034 50.574956 90)
			(size 0.519938 1.4986)
			(layers "F.Cu" "F.Mask" "F.Paste")
			(net "GND")
		)
		(pad "274" smd rect
			(at 2.050034 51.425094 90)
			(size 0.519938 1.4986)
			(layers "F.Cu" "F.Mask" "F.Paste")
			(net "M_I_CPU0_SB_DQ<22>")
		)
		(pad "275" smd rect
			(at 2.050034 52.274978 90)
			(size 0.519938 1.4986)
			(layers "F.Cu" "F.Mask" "F.Paste")
			(net "GND")
		)
		(pad "276" smd rect
			(at 2.050034 53.125116 90)
			(size 0.519938 1.4986)
			(layers "F.Cu" "F.Mask" "F.Paste")
			(net "M_I_CPU0_SB_DQ<23>")
		)
	)
)
